# T6G (Grand Teton) — schematic netlist excerpt (pin names and nets, part order shuffled) for the footprints in the layout excerpt that follows; sources: Cadence DE-HDL packaged netlist, KiCad conversion of 04192023_DAF0TMB3IC0_F0TG_MB_C_brd_V02_OCP.brd

PC2341  Q_CAP  560PF 50V 10% X7R  pkg C0402  page 147 : A = P12V_E1S_ISET_0_R ; B = GND
C2102  Q_CAP  22UF 4V 20% X6S  pkg C0402  page 74 : A = PVDDIO_P1 ; B = GND

(kicad_pcb
	(version 20260206)
	(generator "pcbnew")
	(generator_version "10.0")
	(general
		(thickness 1.6)
		(legacy_teardrops no)
	)
	(paper "A4")
	(title_block
		(title "04192023_DAF0TMB3IC0_F0TG_MB_C_brd_V02_OCP.brd")
		(comment 1 "Grand Teton / footprints 6079-6080 of 8354")
	)
	(layers
		(0 "F.Cu" signal "TOP")
		(4 "In1.Cu" signal "GND")
		(6 "In2.Cu" signal "IN1")
		(8 "In3.Cu" signal "GND1")
		(10 "In4.Cu" signal "IN2")
		(12 "In5.Cu" signal "GND2")
		(14 "In6.Cu" signal "IN3")
		(16 "In7.Cu" signal "GND3")
		(18 "In8.Cu" signal "VCC")
		(20 "In9.Cu" signal "VCC1")
		(22 "In10.Cu" signal "GND4")
		(24 "In11.Cu" signal "IN4")
		(26 "In12.Cu" signal "GND5")
		(28 "In13.Cu" signal "IN5")
		(30 "In14.Cu" signal "GND6")
		(32 "In15.Cu" signal "IN6")
		(34 "In16.Cu" signal "GND7")
		(2 "B.Cu" signal "BOTTOM")
		(9 "F.Adhes" user "F.Adhesive")
		(11 "B.Adhes" user "B.Adhesive")
		(13 "F.Paste" user "Package Geometry/Pastemask Top")
		(15 "B.Paste" user "Package Geometry/Pastemask Bottom")
		(5 "F.SilkS" user "Ref Des/Silkscreen Top")
		(7 "B.SilkS" user "Ref Des/Silkscreen Bottom")
		(1 "F.Mask" user "Board Geometry/Soldermask Top")
		(3 "B.Mask" user "Board Geometry/Soldermask Bottom")
		(17 "Dwgs.User" user "User.Drawings")
		(19 "Cmts.User" user "User.Comments")
		(21 "Eco1.User" user "User.Eco1")
		(23 "Eco2.User" user "User.Eco2")
		(25 "Edge.Cuts" user "Board Geometry/Outline")
		(27 "Margin" user)
		(31 "F.CrtYd" user "Package Geometry/Place Bound Top")
		(29 "B.CrtYd" user "Package Geometry/Place Bound Bottom")
		(35 "F.Fab" user "Ref Des/Assembly Top")
		(33 "B.Fab" user "Ref Des/Assembly Bottom")
	)
	(footprint ""
		(layer "B.Cu")
		(at 259.565394 -51.213512 -90)
		(property "Reference" "PC2341"
			(at 0 0 90)
			(layer "B.SilkS")
			(hide yes)
			(effects
				(font
					(size 1.27 1.27)
				)
				(justify mirror)
			)
		)
		(property "Value" ""
			(at 0 0 90)
			(layer "B.Fab")
			(effects
				(font
					(size 1.27 1.27)
				)
				(justify mirror)
			)
		)
		(duplicate_pad_numbers_are_jumpers no)
		(fp_line
			(start -0.7874 0.4064)
			(end 0.7874 0.4064)
			(stroke
				(width 0.1524)
				(type default)
			)
			(layer "B.SilkS")
		)
		(fp_line
			(start 0.7874 0.4064)
			(end 0.7874 -0.4064)
			(stroke
				(width 0.1524)
				(type default)
			)
			(layer "B.SilkS")
		)
		(fp_line
			(start -0.7874 -0.4064)
			(end -0.7874 0.4064)
			(stroke
				(width 0.1524)
				(type default)
			)
			(layer "B.SilkS")
		)
		(fp_line
			(start 0.7874 -0.4064)
			(end -0.7874 -0.4064)
			(stroke
				(width 0.1524)
				(type default)
			)
			(layer "B.SilkS")
		)
		(fp_line
			(start -0.67945 0.3048)
			(end -0.120396 0.3048)
			(stroke
				(width 0.1)
				(type default)
			)
			(layer "B.Fab")
		)
		(fp_line
			(start -0.120396 0.3048)
			(end -0.120396 0.2794)
			(stroke
				(width 0.1)
				(type default)
			)
			(layer "B.Fab")
		)
		(fp_line
			(start 0.12065 0.3048)
			(end 0.67945 0.3048)
			(stroke
				(width 0.1)
				(type default)
			)
			(layer "B.Fab")
		)
		(fp_line
			(start 0.67945 0.3048)
			(end 0.67945 -0.305054)
			(stroke
				(width 0.1)
				(type default)
			)
			(layer "B.Fab")
		)
		(fp_line
			(start -0.120396 0.2794)
			(end 0.12065 0.2794)
			(stroke
				(width 0.1)
				(type default)
			)
			(layer "B.Fab")
		)
		(fp_line
			(start 0.12065 0.2794)
			(end 0.12065 0.3048)
			(stroke
				(width 0.1)
				(type default)
			)
			(layer "B.Fab")
		)
		(fp_line
			(start -0.12065 -0.2794)
			(end -0.12065 -0.3048)
			(stroke
				(width 0.1)
				(type default)
			)
			(layer "B.Fab")
		)
		(fp_line
			(start 0.12065 -0.2794)
			(end -0.12065 -0.2794)
			(stroke
				(width 0.1)
				(type default)
			)
			(layer "B.Fab")
		)
		(fp_line
			(start -0.67945 -0.3048)
			(end -0.67945 0.3048)
			(stroke
				(width 0.1)
				(type default)
			)
			(layer "B.Fab")
		)
		(fp_line
			(start -0.12065 -0.3048)
			(end -0.67945 -0.3048)
			(stroke
				(width 0.1)
				(type default)
			)
			(layer "B.Fab")
		)
		(fp_line
			(start 0.12065 -0.305054)
			(end 0.12065 -0.2794)
			(stroke
				(width 0.1)
				(type default)
			)
			(layer "B.Fab")
		)
		(fp_line
			(start 0.67945 -0.305054)
			(end 0.12065 -0.305054)
			(stroke
				(width 0.1)
				(type default)
			)
			(layer "B.Fab")
		)
		(pad "1" smd circle
			(at 0.40005 0 90)
			(size 0 0)
			(layers "B.Cu" "B.Mask" "B.Paste")
			(net "P12V_E1S_ISET_0_R")
		)
		(pad "2" smd circle
			(at -0.40005 0 90)
			(size 0 0)
			(layers "B.Cu" "B.Mask" "B.Paste")
			(net "GND")
		)
	)
	(footprint ""
		(layer "B.Cu")
		(at 102.378764 -259.73024 180)
		(property "Reference" "C2102"
			(at 0 0 0)
			(layer "B.SilkS")
			(hide yes)
			(effects
				(font
					(size 1.27 1.27)
				)
				(justify mirror)
			)
		)
		(property "Value" ""
			(at 0 0 0)
			(layer "B.Fab")
			(effects
				(font
					(size 1.27 1.27)
				)
				(justify mirror)
			)
		)
		(duplicate_pad_numbers_are_jumpers no)
		(fp_line
			(start 0.7874 0.4064)
			(end 0.7874 -0.4064)
			(stroke
				(width 0.1524)
				(type default)
			)
			(layer "B.SilkS")
		)
		(fp_line
			(start 0.7874 -0.4064)
			(end -0.7874 -0.4064)
			(stroke
				(width 0.1524)
				(type default)
			)
			(layer "B.SilkS")
		)
		(fp_line
			(start -0.7874 0.4064)
			(end 0.7874 0.4064)
			(stroke
				(width 0.1524)
				(type default)
			)
			(layer "B.SilkS")
		)
		(fp_line
			(start -0.7874 -0.4064)
			(end -0.7874 0.4064)
			(stroke
				(width 0.1524)
				(type default)
			)
			(layer "B.SilkS")
		)
		(fp_line
			(start 0.67945 0.3048)
			(end 0.67945 -0.305054)
			(stroke
				(width 0.1)
				(type default)
			)
			(layer "B.Fab")
		)
		(fp_line
			(start 0.67945 -0.305054)
			(end 0.12065 -0.305054)
			(stroke
				(width 0.1)
				(type default)
			)
			(layer "B.Fab")
		)
		(fp_line
			(start 0.12065 0.3048)
			(end 0.67945 0.3048)
			(stroke
				(width 0.1)
				(type default)
			)
			(layer "B.Fab")
		)
		(fp_line
			(start 0.12065 0.2794)
			(end 0.12065 0.3048)
			(stroke
				(width 0.1)
				(type default)
			)
			(layer "B.Fab")
		)
		(fp_line
			(start 0.12065 -0.2794)
			(end -0.12065 -0.2794)
			(stroke
				(width 0.1)
				(type default)
			)
			(layer "B.Fab")
		)
		(fp_line
			(start 0.12065 -0.305054)
			(end 0.12065 -0.2794)
			(stroke
				(width 0.1)
				(type default)
			)
			(layer "B.Fab")
		)
		(fp_line
			(start -0.120396 0.3048)
			(end -0.120396 0.2794)
			(stroke
				(width 0.1)
				(type default)
			)
			(layer "B.Fab")
		)
		(fp_line
			(start -0.120396 0.2794)
			(end 0.12065 0.2794)
			(stroke
				(width 0.1)
				(type default)
			)
			(layer "B.Fab")
		)
		(fp_line
			(start -0.12065 -0.2794)
			(end -0.12065 -0.3048)
			(stroke
				(width 0.1)
				(type default)
			)
			(layer "B.Fab")
		)
		(fp_line
			(start -0.12065 -0.3048)
			(end -0.67945 -0.3048)
			(stroke
				(width 0.1)
				(type default)
			)
			(layer "B.Fab")
		)
		(fp_line
			(start -0.67945 0.3048)
			(end -0.120396 0.3048)
			(stroke
				(width 0.1)
				(type default)
			)
			(layer "B.Fab")
		)
		(fp_line
			(start -0.67945 -0.3048)
			(end -0.67945 0.3048)
			(stroke
				(width 0.1)
				(type default)
			)
			(layer "B.Fab")
		)
		(pad "1" smd circle
			(at 0.40005 0)
			(size 0 0)
			(layers "B.Cu" "B.Mask" "B.Paste")
			(net "PVDDIO_P1")
		)
		(pad "2" smd circle
			(at -0.40005 0)
			(size 0 0)
			(layers "B.Cu" "B.Mask" "B.Paste")
			(net "GND")
		)
	)
)
